(kicad_pcb
	(version 20241229)
	(generator "pcbnew")
	(generator_version "9.0")
	(general
		(thickness 1.294)
		(legacy_teardrops no)
	)
	(paper "A3")
	(title_block
		(title "Kintex 410T devboard")
		(date "2024-04-03")
		(rev "1.1.2")
		(comment 9 "footprints 940-945 of 975")
	)
	(layers
		(0 "F.Cu" mixed)
		(4 "In1.Cu" power)
		(6 "In2.Cu" power)
		(8 "In3.Cu" mixed)
		(10 "In4.Cu" power)
		(12 "In5.Cu" mixed)
		(14 "In6.Cu" power)
		(16 "In7.Cu" mixed)
		(18 "In8.Cu" power)
		(2 "B.Cu" mixed)
		(9 "F.Adhes" user "F.Adhesive")
		(11 "B.Adhes" user "B.Adhesive")
		(13 "F.Paste" user)
		(15 "B.Paste" user)
		(5 "F.SilkS" user "F.Silkscreen")
		(7 "B.SilkS" user "B.Silkscreen")
		(1 "F.Mask" user)
		(3 "B.Mask" user)
		(17 "Dwgs.User" user "User.Drawings")
		(19 "Cmts.User" user "User.Comments")
		(21 "Eco1.User" user "User.Eco1")
		(23 "Eco2.User" user "User.Eco2")
		(25 "Edge.Cuts" user)
		(27 "Margin" user)
		(31 "F.CrtYd" user "F.Courtyard")
		(29 "B.CrtYd" user "B.Courtyard")
		(35 "F.Fab" user)
		(33 "B.Fab" user)
	)
	(footprint "antmicro-footprints:C_0402_1005Metric"
		(layer "B.Cu")
		(at 164.85 188.3 -90)
		(descr "Capacitor SMD 0402")
		(tags "capacitor SMD 0402")
		(property "Reference" "C337"
			(at -1.6 0.45 90)
			(layer "B.SilkS")
			(effects
				(font
					(size 0.7 0.7)
					(thickness 0.15)
				)
				(justify left bottom mirror)
			)
		)
		(property "Value" "C_100n_0402"
			(at 0 -1.4 90)
			(layer "B.Fab")
			(effects
				(font
					(size 0.7 0.7)
					(thickness 0.15)
				)
				(justify left bottom mirror)
			)
		)
		(property "Description" "SMD Multilayer Ceramic Capacitor, 0.1 µF, 50 V, 0402 [1005 Metric], ± 10%, X5R, GRM Series"
			(at 0 0 270)
			(layer "F.Fab")
			(hide yes)
			(effects
				(font
					(size 1.27 1.27)
					(thickness 0.15)
				)
			)
		)
		(property "Author" "Antmicro"
			(at -23.45 353.15 0)
			(layer "B.Fab")
			(hide yes)
			(effects
				(font
					(size 1 1)
					(thickness 0.15)
				)
				(justify mirror)
			)
		)
		(property "Dielectric" "X5R"
			(at -23.45 353.15 0)
			(layer "B.Fab")
			(hide yes)
			(effects
				(font
					(size 1 1)
					(thickness 0.15)
				)
				(justify mirror)
			)
		)
		(property "License" "Apache-2.0"
			(at -23.45 353.15 0)
			(layer "B.Fab")
			(hide yes)
			(effects
				(font
					(size 1 1)
					(thickness 0.15)
				)
				(justify mirror)
			)
		)
		(property "MPN" "GRM155R61H104KE14D"
			(at -23.45 353.15 0)
			(layer "B.Fab")
			(hide yes)
			(effects
				(font
					(size 1 1)
					(thickness 0.15)
				)
				(justify mirror)
			)
		)
		(property "Manufacturer" "Murata"
			(at -23.45 353.15 0)
			(layer "B.Fab")
			(hide yes)
			(effects
				(font
					(size 1 1)
					(thickness 0.15)
				)
				(justify mirror)
			)
		)
		(property "Val" "100n"
			(at -23.45 353.15 0)
			(layer "B.Fab")
			(hide yes)
			(effects
				(font
					(size 1 1)
					(thickness 0.15)
				)
				(justify mirror)
			)
		)
		(property "Voltage" "50V"
			(at -23.45 353.15 0)
			(layer "B.Fab")
			(hide yes)
			(effects
				(font
					(size 1 1)
					(thickness 0.15)
				)
				(justify mirror)
			)
		)
		(sheetname "DC-DC Converters")
		(sheetfile "dc-dc.kicad_sch")
		(attr smd)
		(fp_rect
			(start -0.925 0.47)
			(end 0.925 -0.47)
			(stroke
				(width 0.05)
				(type default)
			)
			(fill no)
			(layer "B.CrtYd")
		)
		(fp_line
			(start -0.494 0.25)
			(end 0.504 0.25)
			(stroke
				(width 0.15)
				(type solid)
			)
			(layer "B.Fab")
		)
		(fp_line
			(start 0.504 0.25)
			(end 0.504 -0.248)
			(stroke
				(width 0.15)
				(type solid)
			)
			(layer "B.Fab")
		)
		(fp_line
			(start -0.494 -0.248)
			(end -0.494 0.25)
			(stroke
				(width 0.15)
				(type solid)
			)
			(layer "B.Fab")
		)
		(fp_line
			(start 0.504 -0.248)
			(end -0.494 -0.248)
			(stroke
				(width 0.15)
				(type solid)
			)
			(layer "B.Fab")
		)
		(pad "1" smd roundrect
			(at -0.48 0 270)
			(size 0.59 0.64)
			(layers "B.Cu" "B.Mask" "B.Paste")
			(roundrect_rratio 0.25)
			(net 1 "GND")
			(pintype "passive")
		)
		(pad "2" smd roundrect
			(at 0.48 0 270)
			(size 0.59 0.64)
			(layers "B.Cu" "B.Mask" "B.Paste")
			(roundrect_rratio 0.25)
			(net 37 "+3V3_AON")
			(pintype "passive")
		)
	)
	(footprint "antmicro-footprints:C_0201"
		(layer "B.Cu")
		(at 192.3 124.2 -45)
		(descr "Capacitor SMD 0201")
		(tags "capacitor SMD 0201")
		(property "Reference" "C104"
			(at -4.454773 -36.097801 315)
			(unlocked yes)
			(layer "B.SilkS")
			(effects
				(font
					(size 0.7 0.7)
					(thickness 0.15)
				)
				(justify left bottom mirror)
			)
		)
		(property "Value" "C_100n_0201"
			(at 0 -1.399999 135)
			(layer "B.Fab")
			(effects
				(font
					(size 0.7 0.7)
					(thickness 0.15)
				)
				(justify left bottom mirror)
			)
		)
		(property "Description" "SMD Multilayer Ceramic Capacitor, 0.1 µF, 6.3 V, 0201 [0603 Metric], ± 10%, X6S, CC Series"
			(at 0 0 315)
			(layer "F.Fab")
			(hide yes)
			(effects
				(font
					(size 1.27 1.27)
					(thickness 0.15)
				)
			)
		)
		(property "Author" "Antmicro"
			(at -31.499296 172.353971 0)
			(layer "B.Fab")
			(hide yes)
			(effects
				(font
					(size 1 1)
					(thickness 0.15)
				)
				(justify mirror)
			)
		)
		(property "Dielectric" ""
			(at -31.499296 172.353971 0)
			(layer "B.Fab")
			(hide yes)
			(effects
				(font
					(size 1 1)
					(thickness 0.15)
				)
				(justify mirror)
			)
		)
		(property "License" "Apache-2.0"
			(at -31.499296 172.353971 0)
			(layer "B.Fab")
			(hide yes)
			(effects
				(font
					(size 1 1)
					(thickness 0.15)
				)
				(justify mirror)
			)
		)
		(property "MPN" "CC0201KRX6S5BB104"
			(at -31.499296 172.353971 0)
			(layer "B.Fab")
			(hide yes)
			(effects
				(font
					(size 1 1)
					(thickness 0.15)
				)
				(justify mirror)
			)
		)
		(property "Manufacturer" "YAGEO"
			(at -31.499296 172.353971 0)
			(layer "B.Fab")
			(hide yes)
			(effects
				(font
					(size 1 1)
					(thickness 0.15)
				)
				(justify mirror)
			)
		)
		(property "Val" "100n"
			(at -31.499296 172.353971 0)
			(layer "B.Fab")
			(hide yes)
			(effects
				(font
					(size 1 1)
					(thickness 0.15)
				)
				(justify mirror)
			)
		)
		(property "Voltage" ""
			(at -31.499296 172.353971 0)
			(layer "B.Fab")
			(hide yes)
			(effects
				(font
					(size 1 1)
					(thickness 0.15)
				)
				(justify mirror)
			)
		)
		(sheetname "FPGA supply")
		(sheetfile "fpga-supply.kicad_sch")
		(attr smd)
		(fp_poly
			(pts
				(xy -0.7 0.35) (xy 0.7 0.35) (xy 0.7 -0.35) (xy -0.7 -0.35)
			)
			(stroke
				(width 0.05)
				(type default)
			)
			(fill no)
			(layer "B.CrtYd")
		)
		(fp_poly
			(pts
				(xy 0.3 -0.15) (xy -0.301 -0.15) (xy -0.301 0.149) (xy 0.3 0.149)
			)
			(stroke
				(width 0.15)
				(type solid)
			)
			(fill no)
			(layer "B.Fab")
		)
		(pad "" smd roundrect
			(at -0.349 0.002 315)
			(size 0.318 0.36)
			(layers "B.Paste")
			(roundrect_rratio 0.25)
		)
		(pad "" smd roundrect
			(at 0.341 0.002 315)
			(size 0.318 0.36)
			(layers "B.Paste")
			(roundrect_rratio 0.25)
		)
		(pad "1" smd roundrect
			(at -0.321 0.002 315)
			(size 0.46 0.4)
			(layers "B.Cu" "B.Mask")
			(roundrect_rratio 0.25)
			(net 6 "+1V0_MGTAVCC")
			(pintype "passive")
		)
		(pad "2" smd roundrect
			(at 0.32 0.002 315)
			(size 0.46 0.4)
			(layers "B.Cu" "B.Mask")
			(roundrect_rratio 0.25)
			(net 1 "GND")
			(pintype "passive")
		)
	)
	(footprint "antmicro-footprints:R_0402_1005Metric"
		(layer "B.Cu")
		(at 253.601 170.9 90)
		(descr "Resistor SMD 0402")
		(tags "resistor SMD 0402")
		(property "Reference" "R167"
			(at 1.3 -0.501 90)
			(layer "B.SilkS")
			(effects
				(font
					(size 0.7 0.7)
					(thickness 0.15)
				)
				(justify left bottom mirror)
			)
		)
		(property "Value" "R_10k_0402"
			(at 0 -1.4 270)
			(layer "B.Fab")
			(effects
				(font
					(size 0.7 0.7)
					(thickness 0.15)
				)
				(justify left bottom mirror)
			)
		)
		(property "Description" "SMD Chip Resistor, 10 kohm, ± 1%, 62.5 mW, 0402 [1005 Metric], Thick Film, General Purpose"
			(at 0 0 90)
			(layer "F.Fab")
			(hide yes)
			(effects
				(font
					(size 1.27 1.27)
					(thickness 0.15)
				)
			)
		)
		(property "Author" "Antmicro"
			(at 424.501 -82.701 0)
			(layer "B.Fab")
			(hide yes)
			(effects
				(font
					(size 1 1)
					(thickness 0.15)
				)
				(justify mirror)
			)
		)
		(property "License" "Apache-2.0"
			(at 424.501 -82.701 0)
			(layer "B.Fab")
			(hide yes)
			(effects
				(font
					(size 1 1)
					(thickness 0.15)
				)
				(justify mirror)
			)
		)
		(property "MPN" "CR0402-FX-1002GLF"
			(at 424.501 -82.701 0)
			(layer "B.Fab")
			(hide yes)
			(effects
				(font
					(size 1 1)
					(thickness 0.15)
				)
				(justify mirror)
			)
		)
		(property "Manufacturer" "Bourns"
			(at 424.501 -82.701 0)
			(layer "B.Fab")
			(hide yes)
			(effects
				(font
					(size 1 1)
					(thickness 0.15)
				)
				(justify mirror)
			)
		)
		(property "Tolerance" "1%"
			(at 424.501 -82.701 0)
			(layer "B.Fab")
			(hide yes)
			(effects
				(font
					(size 1 1)
					(thickness 0.15)
				)
				(justify mirror)
			)
		)
		(property "Val" "10k"
			(at 424.501 -82.701 0)
			(layer "B.Fab")
			(hide yes)
			(effects
				(font
					(size 1 1)
					(thickness 0.15)
				)
				(justify mirror)
			)
		)
		(sheetname "Power supply")
		(sheetfile "power-supply.kicad_sch")
		(attr smd)
		(fp_rect
			(start -0.925 0.47)
			(end 0.925 -0.47)
			(stroke
				(width 0.05)
				(type default)
			)
			(fill no)
			(layer "B.CrtYd")
		)
		(fp_rect
			(start -0.5 0.25)
			(end 0.5 -0.25)
			(stroke
				(width 0.15)
				(type solid)
			)
			(fill no)
			(layer "B.Fab")
		)
		(pad "1" smd roundrect
			(at -0.48 0 90)
			(size 0.59 0.64)
			(layers "B.Cu" "B.Mask" "B.Paste")
			(roundrect_rratio 0.25)
			(net 699 "GNDD")
			(pintype "passive")
		)
		(pad "2" smd roundrect
			(at 0.48 0 90)
			(size 0.59 0.64)
			(layers "B.Cu" "B.Mask" "B.Paste")
			(roundrect_rratio 0.25)
			(net 889 "/Power supply/PG")
			(pintype "passive")
		)
	)
	(footprint "antmicro-footprints:C_0201"
		(layer "B.Cu")
		(at 190 129.5 180)
		(descr "Capacitor SMD 0201")
		(tags "capacitor SMD 0201")
		(property "Reference" "C159"
			(at 0.575 -0.35 0)
			(layer "B.SilkS")
			(effects
				(font
					(size 0.7 0.7)
					(thickness 0.15)
				)
				(justify left bottom mirror)
			)
		)
		(property "Value" "C_100n_0201"
			(at 0 -1.4 0)
			(layer "B.Fab")
			(effects
				(font
					(size 0.7 0.7)
					(thickness 0.15)
				)
				(justify left bottom mirror)
			)
		)
		(property "Description" "SMD Multilayer Ceramic Capacitor, 0.1 µF, 6.3 V, 0201 [0603 Metric], ± 10%, X6S, CC Series"
			(at 0 0 180)
			(layer "F.Fab")
			(hide yes)
			(effects
				(font
					(size 1.27 1.27)
					(thickness 0.15)
				)
			)
		)
		(property "Author" "Antmicro"
			(at 380 259 0)
			(layer "B.Fab")
			(hide yes)
			(effects
				(font
					(size 1 1)
					(thickness 0.15)
				)
				(justify mirror)
			)
		)
		(property "Dielectric" ""
			(at 380 259 0)
			(layer "B.Fab")
			(hide yes)
			(effects
				(font
					(size 1 1)
					(thickness 0.15)
				)
				(justify mirror)
			)
		)
		(property "License" "Apache-2.0"
			(at 380 259 0)
			(layer "B.Fab")
			(hide yes)
			(effects
				(font
					(size 1 1)
					(thickness 0.15)
				)
				(justify mirror)
			)
		)
		(property "MPN" "CC0201KRX6S5BB104"
			(at 380 259 0)
			(layer "B.Fab")
			(hide yes)
			(effects
				(font
					(size 1 1)
					(thickness 0.15)
				)
				(justify mirror)
			)
		)
		(property "Manufacturer" "YAGEO"
			(at 380 259 0)
			(layer "B.Fab")
			(hide yes)
			(effects
				(font
					(size 1 1)
					(thickness 0.15)
				)
				(justify mirror)
			)
		)
		(property "Val" "100n"
			(at 380 259 0)
			(layer "B.Fab")
			(hide yes)
			(effects
				(font
					(size 1 1)
					(thickness 0.15)
				)
				(justify mirror)
			)
		)
		(property "Voltage" ""
			(at 380 259 0)
			(layer "B.Fab")
			(hide yes)
			(effects
				(font
					(size 1 1)
					(thickness 0.15)
				)
				(justify mirror)
			)
		)
		(sheetname "FPGA supply")
		(sheetfile "fpga-supply.kicad_sch")
		(attr smd)
		(fp_rect
			(start -0.7 0.35)
			(end 0.7 -0.35)
			(stroke
				(width 0.05)
				(type default)
			)
			(fill no)
			(layer "B.CrtYd")
		)
		(fp_rect
			(start 0.3 -0.15)
			(end -0.301 0.149)
			(stroke
				(width 0.15)
				(type solid)
			)
			(fill no)
			(layer "B.Fab")
		)
		(pad "" smd roundrect
			(at -0.349 0.002 180)
			(size 0.318 0.36)
			(layers "B.Paste")
			(roundrect_rratio 0.25)
		)
		(pad "" smd roundrect
			(at 0.341 0.002 180)
			(size 0.318 0.36)
			(layers "B.Paste")
			(roundrect_rratio 0.25)
		)
		(pad "1" smd roundrect
			(at -0.321 0.002 180)
			(size 0.46 0.4)
			(layers "B.Cu" "B.Mask")
			(roundrect_rratio 0.25)
			(net 1 "GND")
			(pintype "passive")
		)
		(pad "2" smd roundrect
			(at 0.32 0.002 180)
			(size 0.46 0.4)
			(layers "B.Cu" "B.Mask")
			(roundrect_rratio 0.25)
			(net 8 "+1V2_MGTAVTT")
			(pintype "passive")
		)
	)
	(footprint "antmicro-footprints:R_Array_4x0201_Panasonic_EXB18V"
		(layer "B.Cu")
		(at 218.1 132.8 -90)
		(property "Reference" "R36"
			(at 1.1 -1.5 90)
			(layer "B.SilkS")
			(effects
				(font
					(size 0.7 0.7)
					(thickness 0.15)
				)
				(justify right bottom mirror)
			)
		)
		(property "Value" "4x10k_0201_array"
			(at -1.1 -1.8 90)
			(layer "B.Fab")
			(effects
				(font
					(size 0.7 0.7)
					(thickness 0.15)
				)
				(justify left bottom mirror)
			)
		)
		(property "Description" "Fixed Network Resistor, 10 kohm, Isolated, 4 Resistors, 0502 [1406 Metric], Flat, ± 5%"
			(at 0 0 270)
			(layer "F.Fab")
			(hide yes)
			(effects
				(font
					(size 1.27 1.27)
					(thickness 0.15)
				)
			)
		)
		(property "Author" "Antmicro"
			(at 85.3 350.9 0)
			(layer "B.Fab")
			(hide yes)
			(effects
				(font
					(size 1 1)
					(thickness 0.15)
				)
				(justify mirror)
			)
		)
		(property "License" "Apache-2.0"
			(at 85.3 350.9 0)
			(layer "B.Fab")
			(hide yes)
			(effects
				(font
					(size 1 1)
					(thickness 0.15)
				)
				(justify mirror)
			)
		)
		(property "MPN" "EXB-18V103JX"
			(at 85.3 350.9 0)
			(layer "B.Fab")
			(hide yes)
			(effects
				(font
					(size 1 1)
					(thickness 0.15)
				)
				(justify mirror)
			)
		)
		(property "Manufacturer" "Panasonic"
			(at 85.3 350.9 0)
			(layer "B.Fab")
			(hide yes)
			(effects
				(font
					(size 1 1)
					(thickness 0.15)
				)
				(justify mirror)
			)
		)
		(property "Val" "4x10k_0201"
			(at 85.3 350.9 0)
			(layer "B.Fab")
			(hide yes)
			(effects
				(font
					(size 1 1)
					(thickness 0.15)
				)
				(justify mirror)
			)
		)
		(sheetname "DRAM + SRAM")
		(sheetfile "ram.kicad_sch")
		(attr smd)
		(fp_line
			(start -0.8 0.45)
			(end -0.8 -0.45)
			(stroke
				(width 0.12)
				(type solid)
			)
			(layer "B.SilkS")
		)
		(fp_line
			(start 0.8 0.45)
			(end 0.8 -0.45)
			(stroke
				(width 0.12)
				(type solid)
			)
			(layer "B.SilkS")
		)
		(fp_rect
			(start -0.898 0.66)
			(end 0.898 -0.65)
			(stroke
				(width 0.05)
				(type solid)
			)
			(fill no)
			(layer "B.CrtYd")
		)
		(pad "1" smd roundrect
			(at -0.6 -0.298 270)
			(size 0.2 0.4)
			(layers "B.Cu" "B.Mask" "B.Paste")
			(roundrect_rratio 0.25)
			(net 563 "/DRAM + SRAM/SRAM.~{WE}")
			(pinfunction "R1.1")
			(pintype "passive")
		)
		(pad "2" smd roundrect
			(at -0.202 -0.298 270)
			(size 0.2 0.4)
			(layers "B.Cu" "B.Mask" "B.Paste")
			(roundrect_rratio 0.25)
			(net 564 "/DRAM + SRAM/SRAM.~{OE}")
			(pinfunction "R2.1")
			(pintype "passive")
		)
		(pad "3" smd roundrect
			(at 0.2 -0.298 270)
			(size 0.2 0.4)
			(layers "B.Cu" "B.Mask" "B.Paste")
			(roundrect_rratio 0.25)
			(net 556 "/DRAM + SRAM/SRAM.~{CE}")
			(pinfunction "R3.1")
			(pintype "passive")
		)
		(pad "4" smd roundrect
			(at 0.598 -0.298 270)
			(size 0.2 0.4)
			(layers "B.Cu" "B.Mask" "B.Paste")
			(roundrect_rratio 0.25)
			(net 562 "/DRAM + SRAM/SRAM.CE2")
			(pinfunction "R4.1")
			(pintype "passive")
		)
		(pad "5" smd roundrect
			(at 0.598 0.3 270)
			(size 0.2 0.4)
			(layers "B.Cu" "B.Mask" "B.Paste")
			(roundrect_rratio 0.25)
			(net 24 "+3V3")
			(pinfunction "R4.2")
			(pintype "passive")
		)
		(pad "6" smd roundrect
			(at 0.2 0.3 270)
			(size 0.2 0.4)
			(layers "B.Cu" "B.Mask" "B.Paste")
			(roundrect_rratio 0.25)
			(net 24 "+3V3")
			(pinfunction "R3.2")
			(pintype "passive")
		)
		(pad "7" smd roundrect
			(at -0.202 0.3 270)
			(size 0.2 0.4)
			(layers "B.Cu" "B.Mask" "B.Paste")
			(roundrect_rratio 0.25)
			(net 24 "+3V3")
			(pinfunction "R2.2")
			(pintype "passive")
		)
		(pad "8" smd roundrect
			(at -0.6 0.3 270)
			(size 0.2 0.4)
			(layers "B.Cu" "B.Mask" "B.Paste")
			(roundrect_rratio 0.25)
			(net 24 "+3V3")
			(pinfunction "R1.2")
			(pintype "passive")
		)
	)
	(footprint "antmicro-footprints:R_0402_1005Metric"
		(layer "B.Cu")
		(at 258.4 79 -90)
		(descr "Resistor SMD 0402")
		(tags "resistor SMD 0402")
		(property "Reference" "R359"
			(at -1.4 -1.3 90)
			(layer "B.SilkS")
			(effects
				(font
					(size 0.7 0.7)
					(thickness 0.15)
				)
				(justify left bottom mirror)
			)
		)
		(property "Value" "R_100k_0402"
			(at 0 -1.4 90)
			(layer "B.Fab")
			(effects
				(font
					(size 0.7 0.7)
					(thickness 0.15)
				)
				(justify left bottom mirror)
			)
		)
		(property "Description" "SMD Chip Resistor, 100 kohm, ± 1%, 62.5 mW, 0402 [1005 Metric], Thick Film, General Purpose"
			(at 0 0 270)
			(layer "F.Fab")
			(hide yes)
			(effects
				(font
					(size 1.27 1.27)
					(thickness 0.15)
				)
			)
		)
		(property "Author" "Antmicro"
			(at 179.4 337.4 0)
			(layer "B.Fab")
			(hide yes)
			(effects
				(font
					(size 1 1)
					(thickness 0.15)
				)
				(justify mirror)
			)
		)
		(property "License" "Apache-2.0"
			(at 179.4 337.4 0)
			(layer "B.Fab")
			(hide yes)
			(effects
				(font
					(size 1 1)
					(thickness 0.15)
				)
				(justify mirror)
			)
		)
		(property "MPN" "CR0402-FX-1003GLF"
			(at 179.4 337.4 0)
			(layer "B.Fab")
			(hide yes)
			(effects
				(font
					(size 1 1)
					(thickness 0.15)
				)
				(justify mirror)
			)
		)
		(property "Manufacturer" "Bourns"
			(at 179.4 337.4 0)
			(layer "B.Fab")
			(hide yes)
			(effects
				(font
					(size 1 1)
					(thickness 0.15)
				)
				(justify mirror)
			)
		)
		(property "Tolerance" "1%"
			(at 179.4 337.4 0)
			(layer "B.Fab")
			(hide yes)
			(effects
				(font
					(size 1 1)
					(thickness 0.15)
				)
				(justify mirror)
			)
		)
		(property "Val" "100k"
			(at 179.4 337.4 0)
			(layer "B.Fab")
			(hide yes)
			(effects
				(font
					(size 1 1)
					(thickness 0.15)
				)
				(justify mirror)
			)
		)
		(sheetname "User GPIO + LED + button + DIP switch")
		(sheetfile "user-gpio.kicad_sch")
		(attr smd)
		(fp_rect
			(start -0.925 0.47)
			(end 0.925 -0.47)
			(stroke
				(width 0.05)
				(type default)
			)
			(fill no)
			(layer "B.CrtYd")
		)
		(fp_rect
			(start -0.5 0.25)
			(end 0.5 -0.25)
			(stroke
				(width 0.15)
				(type solid)
			)
			(fill no)
			(layer "B.Fab")
		)
		(pad "1" smd roundrect
			(at -0.48 0 270)
			(size 0.59 0.64)
			(layers "B.Cu" "B.Mask" "B.Paste")
			(roundrect_rratio 0.25)
			(net 1305 "/USER_IO.LED_RED")
			(pintype "passive")
		)
		(pad "2" smd roundrect
			(at 0.48 0 270)
			(size 0.59 0.64)
			(layers "B.Cu" "B.Mask" "B.Paste")
			(roundrect_rratio 0.25)
			(net 1 "GND")
			(pintype "passive")
		)
	)
)
